;LEADER: 12 
;HEADER: 
;CODE  : ASCII 
;FILE  : 9324_DA0F0TMBIJ0_F0T_Motherboard_J_v01_20230324_0910-bd-1-15.drl for backdrilling ... from layer TOP to layer GND6
;DESIGN: 9324_DA0F0TMBIJ0_F0T_Motherboard_J_v01_20230324_0910.brd
;MUST-NOT-CUT-LAYER = IN6,  MAX_DRILL_DEPTH = 83.20 MILS,  MFG_STUB_LENGTH = 0.00 MILS
;   BackdrillSize 1. = 17.700000 Tolerance = +0.000000/-0.000000 NON_PLATED MILS Quantity = 12
%
G90
X0064410Y1599102
X0064410Y1602502
X0045812Y0451602
X0049212Y0451602
X1032433Y-0009811
X1032433Y-0013211
X1341752Y-0013211
X1341752Y-0009811
X1290291Y-0009811
X1290291Y-0013211
X1482650Y-0013211
X1482650Y-0009811
M30
